FILE_TYPE = MULTI_PHYS_TABLE;

PART 'XTAL_4'
CLASS=DISCRETE

{========================================================================================}
:CLS_PN             = JEDEC_TYPE                 | ALT_SYMBOLS                 | DESCRIPTION                                                                                    | CPN_STATUS ;
{========================================================================================}
 'CL4000014A'       = ''                         | '()'                        | 'XTAL, 12.000000 MHZ, 18.0PF, +10.0-10.0PPM'                                                   |''
 'CL4000015A'       = ''                         | '()'                        | 'XTAL, 24.000000 MHZ, 18.0PF, +10.0-10.0PPM'                                                   |''
 'CL4000016A'       = ''                         | '()'                        | 'XTAL, 25.000000 MHZ, 18.0PF, +10.0-10.0PPM'                                                   |''
 'CL5000020A'       = 'TBD'                      | '(TBD)'                     | 'XTAL, 12MHZ, 18PF, ¡À30PPM, 100OHM, 100UW, -20¡ÃC~+70¡ÃC, 3.2*2.5MM, SMD, ROHS'                |''
 'CL4000063A'       = 'SMC_XTAL4_126X098_V2'     | '(SMC_XTAL4_126X098_V2)'    | 'XTAL, 12.000000 MHZ, 18.0PF, +-10PPM, -40C~+85C, ROHS'                                        |''
 'CL4000064A'       = 'SMC_XTAL4_126X098_V2'     | '(SMC_XTAL4_126X098_V2)'    | 'XTAL, 24.000000 MHZ, 18.0PF, +-10PPM, -40C~+85C, ROHS'                                        |''
 'CL4000065A'       = 'SMC_XTAL4_126X098_V2'     | '(SMC_XTAL4_126X098_V2)'    | 'XTAL, 25.000000 MHZ, 18.0PF, +-10PPM, -40C~+85C, ROHS'                                        |''
 'CL5001016A'       = 'SMC_OSC4_098X079'         | '(SMC_OSC4_098X079)'        | 'XTAL, 13MHZ, 20PPM, 12PF, 150OHM, 2520'                                                       |''
 'CL5001023A'       = 'SMC_OSC4_098X079'         | '(SMC_OSC4_098X079)'        | 'XTAL, 24.576MHZ, 20PPM, 12PF, 2520'                                                           |''
 'CL5002012A'       = 'SMC_Y4_197X126'           | '(SMC_Y4_197X126)'          | 'CRYSTAL, MINIATURE QUARTZ, 5X3.2MM, CERAMIC, SMD, 24.16139MHZ'                                |''
 'CL5002006A'       = 'SMC_XTAL4_126X098_V1'     | '(SMC_XTAL4_126X098_V1)'    | 'XTAL, 26MHZ, MINIATURE QUARTZ, 3.2X2.5MM, CERAMIC'                                            |''
 'G131-00016-01'    = 'SMC_XTAL4_126X098_V1'     | '(SMC_XTAL4_126X098_V1)'    | 'XTAL, 26MHZ, MINIATURE QUARTZ, 3.2X2.5MM, CERAMIC'                                            |''
 'CL5002046A'       = 'SMC_XTAL4_126X098_V2'     | '(SMC_XTAL4_126X098_V2)'    | 'XTAL, 32.000MHZ, 12PF, 10PPM, -20 TO +70'                                                     |''
 'G131-10011-01'    = 'SMC_Y4_126X098_V1'        | '(SMC_Y4_126X098_V1)'       | 'XTAL,25.000MHZ,18PF,50PPM,SIZE 3.2X2.5X0.6MM,4 PADS SMD'                                      |'NFND'
 'G131-10013-01'    = 'SMC_Y4_126X098_H0295'     | '(SMC_Y4_126X098_H0295)'    | 'XTAL, 26MHZ,18PF,30PPM, 3.2X2.5MM,SMT'                                                        |''
 'G131-10014-01'    = 'SMC_Y4_126X098_V1'        | '(SMC_Y4_126X098_V1)'       | 'XTAL,25.000MHZ,18PF,FUNDAMENTAL,25PPM,SIZE 3.2X2.5X0.6MM,4 PADS SMD,ROHS COMPLIANT,LEAD FREE' |''
 'G131-10016-01'    = 'SMC_Y4_126X098_V3'        | '(SMC_Y4_126X098_V3)'       | 'XTAL,25.000MHZ,18PF,FUNDAMENTAL,15PPM,SIZE 3.2X2.5X0.6MM,4 PADS SMD,ROHS COMPLIANT,LEAD FREE' |'NFND'
 'G131-10017-01'    = 'SMC_Y4_236X138_V2'        | '(SMC_Y4_236X138_V2)'       | 'XTAL, 25MHZ, 20PPM, 18PF, SMT'                                                                |'NFND'
 'G131-10025-01'    = 'SMC_Y4_197X126_V2'        | '(SMC_Y4_197X126_V2)'       | 'XTAL, 14.318MHZ, 20PF, +/-30PPM, SMD,5.0X3.2X1.0'                                             |'NFND'
 'G131-10026-01'    = 'SMC_Y4_126X098_V1'        | '(SMC_Y4_126X098_V1)'       | 'XTAL, 25.000000MHZ, 10PF, +/-10PPM, 3.2MMX2.5MMX0.6MM'                                        |'NFND'
 'G131-10027-01'    = 'SMC_Y4_126X098_V1'        | '(SMC_Y4_126X098_V1)'       | 'XTAL, 25.000MHZ, 10PF, +/-25PPM, SMD, 3.2MMX2.5MMX0.6MM'                                      |'NFND'
 'G131-10031-01'    = 'SMC_Y4_126X098_H0295'     | '(SMC_Y4_126X098_H0295)'    | 'XTAL,25.000MHZ,12PF,30PPM,SIZE 3.2X2.5X0.75MM,4 PADS SMD'                                     |''
 'G131-10038-01'    = 'SMC_Y4_126X098_V5_H032'   | '(SMC_Y4_126X098_V5_H032)'  | 'XTAL,12MHZ,18PF,20PPM,3.2MMX2.5MM,SMT'                                                        |''
 'G131-10022-01'    = 'SMC_Y4_126X098_V5'        | '(SMC_Y4_126X098_V5)'       | 'XTAL, 25MHZ, 12PF, 20PPM, 3.2*2.5MM'                                                          |''
 'G131-10039-01'    = 'SMC_Y4_126X098_V5_H032'   | '(SMC_Y4_126X098_V5_H032)'  | 'XTAL,25.000MHZ,12PF,FUNDAMENTAL,10PPM,SIZE 3.2X2.5X0.7MM,4 PADS SMD,ROHS COMPLIANT,LEAD FREE' |''
 'G131-10047-01'    = 'SMC_Y4_197X126_V10'       | '(SMC_Y4_197X126_V10)'      | 'XTAL,25MHZ,10PPM,10PF,-20~70C, 5.0 X 3.2MM,SMT'                                               |'NFND'
 'G131-10048-01'    = 'SMC_Y4_197X126_V11'       | '(SMC_Y4_197X126_V11)'      | 'XTAL,25MHZ,20PPM,10PF,-40~85C,5.0 X 3.2MM,SMT'                                                |'NFND'
 'G131-10049-01'    = 'SMC_Y4_126X098_V3_H031'   | '(SMC_Y4_126X098_V3_H031)'  | 'XTAL,25.000MHZ,18PF,50PPM,SIZE 3.2X2.5X0.8MM,4 PADS SMD'                                      |'NFND'
 'G131-10051-01'    = 'SMC_Y4_126X098_V3_H031'   | '(SMC_Y4_126X098_V3_H031)'  | 'XTAL,24.000MHZ,18PF,50PPM,SIZE 3.2X2.5X0.8MM,4 PADS SMD'                                      |'NFND'
 'G131-10030-01'    = 'SMC_Y4_126X098_V6'        | '(SMC_Y4_126X098_V6)'       | 'XTAL,25.000000MHZ,18PF,20PPM,SMD'                                                             |''
 'G131-10052-01'    = 'SMC_Y4_126X098_V5_H032'   | '(SMC_Y4_126X098_V5_H032)'  | 'XTAL,24.000MHZ,18PF,20PPM,SIZE 3.2X2.5X0.7MM,4 PADS SMD'                                      |''
 'G131-10043-01'    = 'SMC_Y4_126X098_V5_H032'   | '(SMC_Y4_126X098_V5_H032)'  | 'XTAL,48.000000MHZ,10PF,30PPM,3.2MM X 2.5MM,SMT'                                               |''
 'G131-10019-01'    = 'SMC_Y4_126X098_V5'        | '(SMC_Y4_126X098_V5)'       | 'XTAL,25.000000MHZ,12PF,30PPM,SMT4'                                                            |''
 'G131-10053-01'    = 'SMC_Y4_079X063'           | '(SMC_Y4_079X063)'          | 'XTAL,FA-128,32.000MHZ,10PF,-10PPM/+10PPM,SMT'                                                 |''
 'G131-10046-01'    = 'SMC_Y4_197X126_V8'        | '(SMC_Y4_197X126_V8)'       | 'XTAL,25MHZ,18PF,30PPM,5X3.2MM,SMT'                                                            |'NFND'
 'G131-10008-01'    = 'SMC_Y4_236X138_V1'        | '(SMC_Y4_236X138_V1)'       | 'XTAL,25.000MHZ,30PPM/30PPM,18PF,6MMX3.5MM,SMT4'                                               |''
 'G131-10054-01'    = 'SMC_Y4_126X098_V6'        | '(SMC_Y4_126X098_V6)'       | 'XTAL,50MHZ,16PF,10PPM,3.2MMX2.5MMX0.65MM,SMT'                                                 |'NFND'
 'G131-10035-01'    = 'SMC_Y4_126X098_V1'        | '(SMC_Y4_126X098_V1)'       | 'XTAL,25MHZ,10PF,20PPM,3.2X2.5MM,SMD,4PAD'                                                     |'NFND'
 'G131-10057-01'    = 'SMC_Y4_126X098_V6'        | '(SMC_Y4_126X098_V6)'       | 'XTAL,25MHZ,20PF,20PPM,SMT'                                                                    |''
 'G131-10042-01'    = 'SMC_Y4_126X098_V6'        | '(SMC_Y4_126X098_V6)'       | 'XTAL,25MHZ,20PF,20PPM,3.2MMX2.5MMX0.65MM,SMT'                                                 |''
 'G131-10059-01'    = 'SMC_Y4_126X098_V5_H032'   | '(SMC_Y4_126X098_V5_H032)'  | 'XTAL,50.000000MHZ,18PF,10PPM,3.2X2.5MM,SMD'                                                   |''
 'G131-10060-01'    = 'SMC_Y4_126X098_V6_H0315'  | '(SMC_Y4_126X098_V6_H0315)' | 'XTAL,50.000000MHZ,19PF,15PPM,3.2X2.5MM,SMT'                                                   |''
 'G131-10062-01'    = 'SMC_Y4_126X098_V5_H032'   | '(SMC_Y4_126X098_V5_H032)'  | 'XTAL,48MHZ,8PF,20PPM,SMD'                                                                     |''
 'G131-10063-01'    = 'SMC_Y4_126X098_V5_H032'   | '(SMC_Y4_126X098_V5_H032)'  | 'XTAL,48MHZ,8PF,10PPM,SMD'                                                                     |''
 'G131-10064-01'    = 'SMC_Y4_081X065'           | '(SMC_Y4_081X065)'          | 'XTAL,25.0MHZ, 20PF,20/20PPM,0°C TO +100°C,TS 1.6PPM/PF,SMD'                                   |''
 'G131-10065-01'    = 'SMC_Y4_126X098_V5'        | '(SMC_Y4_126X098_V5)'       | 'XTAL, 20MHZ, 16PF, 20PPM, 3.2X2.5MM'                                                          |''
 'G131-10067-01'    = 'SMC_Y4_126X098_V5_H032'   | '(SMC_Y4_126X098_V5_H032)'  | 'XTAL, 25MHZ, 12PF, 20PPM, 3.2*2.5MM'                                                          |''
 'G131-10068-01'    = 'SMC_Y4_126X098_V10'       | '(SMC_Y4_126X098_V10)'      | 'XTAL, 48MHZ, 10PF, 30PPM, 3.2*2.5MM'                                                          |''
 'G131-10069-01'    = 'SMC_Y4_126X098_V3_H031'   | '(SMC_Y4_126X098_V3_H031)'  | 'XTAL,24.000MHZ,18PF,15PPM,SIZE 3.2X2.5X0.6MM,4 PADS SMD'                                      |'NFND'
 'G131-10018-01'    = 'SMC_Y4_126X098_H032'      | '(SMC_Y4_126X098_H032)'     | 'XTAL,48.000MHZ,+/-50PPM,8PF'                                                                  |''
 'G131-10073-01'    = 'SMC_Y4_126X098_V5_H032'   | '(SMC_Y4_126X098_V5_H032)'  | 'XTAL,48.0000MHZ,8PF,10PPM,3.20X2.50MM'                                                        |''
 'P131-10011-01'    = 'SMC_Y4_126X098_V1'        | '(SMC_Y4_126X098_V1)'       | 'XTAL,25MHZ,18PF,50PPM,100OHMESR,3.2X2.5X0.7MM,4 PADS SMD'                                     |''
 'G131-10074-01'    = 'SMC_Y4_126X098_V6_H0315'  | '(SMC_Y4_126X098_V6_H0315)' | 'XTAL,25.000MHZ,18PF,20PPM,3.2X2.5MM'                                                          |''
 'G131-10078-01'    = 'SMC_Y4_197X126_V10'       | '(SMC_Y4_197X126_V10)'      | 'XTAL,14.318MHZ,20PF,30PPM,5MMX3.2MM,SMT'                                                      |'OBSOLETE'
 'G131-10079-01'    = 'SMC_Y4_126X098_V12'       | '(SMC_Y4_126X098_V12)'      | 'XTAL,25.000MHZ,20PPM TOL,18PF,70OHMESR,50PPM STABILITY,3.2X2.5X0.75MM,SMT'                    |''
 'A131-10062-FB'    = 'SMC_Y4_126X098_V5_H032'   | '(SMC_Y4_126X098_V5_H032)'  | 'XTAL,48MHZ,8PF,20PPM,SMD'                                                                     |''
 'G131-10081-01'    = 'SMC_Y4_079X063_V1'        | '(SMC_Y4_079X063_V1)'       | 'XTAL,48MHZ,8.8PF,10PPM,2X1.6 SMD'                                                             |''
 'G131-10082-01'    = 'SMC_Y4_126X098_V12_H315'  | '(SMC_Y4_126X098_V12_H315)' | 'XTAL,25.0MHZ,18PF,10/25PPM,3.2X2.5 CERAMIC SEAM SEAL SMD PACKAGE,-20C~70C'                    |''
 'G131-10083-01'    = 'SMC_Y4_126X098_V12_H028'  | '(SMC_Y4_126X098_V12_H028)' | 'XTAL,25.000MHZ,18PF,25PPM,SIZE 3.2X2.5X0.7MM,4 PADS SMD'                                      |''
 'G131-10022-02'    = 'SMC_Y4_126X098_V5'        | '(SMC_Y4_126X098_V5)'       | 'XTAL,25MHZ,12PF,20PPM,ESR60OHM,-10-70C,3.3*2.6*0.9MM,SMT'                                     |''
 'G131-10038-02'    = 'SMC_Y4_126X098_V5_H032'   | '(SMC_Y4_126X098_V5_H032)'  | 'XTAL,12MHZ,18PF,20PPM,3.2MMX2.5MMX0.8MM,SMT'                                                  |''
 'G131-10011-02'    = 'SMC_Y4_126X098_V3_H031'   | '(SMC_Y4_126X098_V3_H031)'  | 'XTAL,25MHZ,18PF,50PPM,3.2MMX2.5MMX0.8MM,SMT'                                                  |''
 'G131-10076-01'    = 'SMC_Y4_126X098_V5_H032'   | '(SMC_Y4_126X098_V5_H032)'  | 'XTAL,25.0000MHZ,10PF,20PPM,3.2X2.5MM,SMT'                                                     |''
 'G131-10042-02'    = 'SMC_Y4_126X098_V10'       | '(SMC_Y4_126X098_V10)'      | 'XTAL,25MHZ,20PF,20PPM,3.2MMX2.5MMX0.65MM,SMT'                                                 |''
 'G131-10084-01'    = 'SMC_Y4_063X047'           | '(SMC_Y4_063X047)'          | 'XTAL,40.0000MHZ,8PF,30PPM,1.6MMX1.2MM,SMT'                                                    |''
 'G131-10085-01'    = 'SMC_Y4_126X098_V5'        | '(SMC_Y4_126X098_V5)'       | 'XTAL,25.000000MHZ,8PF,10PPM,SMT'                                                              |''

END_PART

END.

